# S9S_MB_2U (Grand Teton) — schematic parts with pin connectivity, parts 5880–5883 of 6093; source: Cadence DE-HDL packaged netlist (pstxprt.dat, pstxnet.dat, pstchip.dat)

U2  SOCKET4677_AZIF0045P001C01CS  SOCKET4677_AZIF0045-P001C01CS IO  pkg SOCKET4677_82X64-5XA_H466  page 13  (pins 4565-4677 of 4677)
  V47  VSS1793  POWER  = GND
  V49  VSS1789  POWER  = GND
  V51  VSS1794  POWER  = GND
  V53  VSS1795  POWER  = GND
  V55  VSS1796  POWER  = GND
  V57  VSS1797  POWER  = GND
  V59  VSS1798  POWER  = GND
  V61  VSS1799  POWER  = GND
  V63  VSS1802  POWER  = GND
  V65  VSS1803  POWER  = GND
  V67  VSS1804  POWER  = GND
  V69  VSS1805  POWER  = GND
  V71  VSS1800  POWER  = GND
  V73  VSS1801  POWER  = GND
  V75  VSS1806  POWER  = GND
  V77  VSS1810  POWER  = GND
  V79  VSS1811  POWER  = GND
  V81  UPI2_TX_DP7  OUT  = UPI_CPU0_CPU1_P2P2_DP<16>
  V83  UPI2_TX_DN8  OUT  = UPI_CPU0_CPU1_P2P2_DN<15>
  V85  PE4_TX_DP3  OUT  = P5E_CPU0_PE4_TX_DP<3>
  V87  VSS1813  POWER  = GND
  V89  PE4_RX_DN3  IN  = P5E_CPU0_PE4_RX_DN<3>
  V91  VSS1807  POWER  = GND
  W1  VSS1808  POWER  = GND
  W3  UPI0_TX_DP5  OUT  = UPI_CPU0_CPU1_P0P1_DP<5>
  W5  VSS1814  POWER  = GND
  W7  UPI0_RX_DP4  IN  = UPI_CPU1_CPU0_P1P0_DP<4>
  W9  VSS1819  POWER  = GND
  W11  PE0_RX_DP4  IN  = P5E_CPU0_PE0_RX_DP<4>
  W13  VSS1809  POWER  = GND
  W15  PE0_TX_DP3  OUT  = P5E_CPU0_PE0_TX_DP<3>
  W17  RSVD165  BI  = NC_CPU0_HBM1_VIEWDIG0
  W19  DDR2_SB_DQ23  BI  = M_C_CPU0_SB_DQ<23>
  W21  DDR2_SB_DQS_DN7  BI  = M_C_CPU0_SB_DQS_DN<7>
  W23  DDR2_SB_DQ18  BI  = M_C_CPU0_SB_DQ<18>
  W25  DDR1_SB_DQ7  BI  = M_B_CPU0_SB_DQ<7>
  W27  DDR1_SB_DQS_DN5  BI  = M_B_CPU0_SB_DQS_DN<5>
  W29  DDR1_SB_DQ2  BI  = M_B_CPU0_SB_DQ<2>
  W31  DDR2_SB_ECC3  BI  = M_C_CPU0_SB_CB<3>
  W33  DDR2_SB_DQS_DN4  BI  = M_C_CPU0_SB_DQS_DN<4>
  W35  DDR2_SB_ECC6  BI  = M_C_CPU0_SB_CB<6>
  W37  DDR2_SB_CS_N3  OUT  = M_C_CPU0_SB_CS_N<3>
  W39  VSS1816  POWER  = GND
  W41  DDR2_SB_CA3  OUT  = M_C_CPU0_SB_CA<3>
  W43  DDR1_SA_PAR  OUT  = M_B_CPU0_SA_PAR
  W45  DDR1_CLK_DN1  OUT  = M_B_CPU0_CLK_DN<1>
  W48  DDR2_SB_CA0  OUT  = M_C_CPU0_SB_CA<0>
  W50  DDR2_SA_CA5  OUT  = M_C_CPU0_SA_CA<5>
  W52  VSS1815  POWER  = GND
  W54  DDR2_SA_CS_N2  OUT  = M_C_CPU0_SA_CS_N<2>
  W56  DDR1_SA_DQ31  BI  = M_B_CPU0_SA_DQ<31>
  W58  DDR1_SA_DQS_DP8  BI  = M_B_CPU0_SA_DQS_DP<8>
  W60  DDR1_SA_DQ26  BI  = M_B_CPU0_SA_DQ<26>
  W62  DDR2_SA_DQ23  BI  = M_C_CPU0_SA_DQ<23>
  W64  DDR2_SA_DQS_DP7  BI  = M_C_CPU0_SA_DQS_DP<7>
  W66  DDR2_SA_DQ18  BI  = M_C_CPU0_SA_DQ<18>
  W68  DDR1_SA_DQ15  BI  = M_B_CPU0_SA_DQ<15>
  W70  DDR1_SA_DQS_DP6  BI  = M_B_CPU0_SA_DQS_DP<6>
  W72  DDR1_SA_DQ10  BI  = M_B_CPU0_SA_DQ<10>
  W74  DDR2_SA_DQ7  BI  = M_C_CPU0_SA_DQ<7>
  W76  DDR2_SA_DQS_DN5  BI  = M_C_CPU0_SA_DQS_DN<5>
  W78  DDR2_SA_DQ2  BI  = M_C_CPU0_SA_DQ<2>
  W80  VCCFA_EHV_FIVRA101  POWER  = PVCCFA_EHV_FIVRA_CPU0
  W82  UPI2_TX_DP9  OUT  = UPI_CPU0_CPU1_P2P2_DP<14>
  W84  VSS1817  POWER  = GND
  W86  PE4_TX_DN4  OUT  = P5E_CPU0_PE4_TX_DN<4>
  W88  VSS1818  POWER  = GND
  W90  PE4_RX_DP4  IN  = P5E_CPU0_PE4_RX_DP<4>
  Y2  UPI0_TX_DN5  OUT  = UPI_CPU0_CPU1_P0P1_DN<5>
  Y4  VSS1826  POWER  = GND
  Y6  UPI0_RX_DP5  IN  = UPI_CPU1_CPU0_P1P0_DN<5>
  Y8  VSS1832  POWER  = GND
  Y10  PE0_RX_DP5  IN  = P5E_CPU0_PE0_RX_DP<5>
  Y12  VSS1820  POWER  = GND
  Y14  PE0_TX_DP4  OUT  = P5E_CPU0_PE0_TX_DP<4>
  Y16  VSS1821  POWER  = GND
  Y18  VSS1822  POWER  = GND
  Y20  DDR2_SB_DQ22  BI  = M_C_CPU0_SB_DQ<22>
  Y22  DDR2_SB_DQ19  BI  = M_C_CPU0_SB_DQ<19>
  Y24  VSS1823  POWER  = GND
  Y26  DDR1_SB_DQ6  BI  = M_B_CPU0_SB_DQ<6>
  Y28  DDR1_SB_DQ3  BI  = M_B_CPU0_SB_DQ<3>
  Y30  VSS1824  POWER  = GND
  Y32  DDR2_SB_ECC2  BI  = M_C_CPU0_SB_CB<2>
  Y34  DDR2_SB_ECC7  BI  = M_C_CPU0_SB_CB<7>
  Y36  VSS1825  POWER  = GND
  Y38  DDR2_SB_CS_N2  OUT  = M_C_CPU0_SB_CS_N<2>
  Y40  DDR2_SB_CA5  OUT  = M_C_CPU0_SB_CA<5>
  Y42  VSS1827  POWER  = GND
  Y44  DDR1_SA_CA6  OUT  = M_B_CPU0_SA_CA<6>
  Y47  DDR2_SB_CA1  OUT  = M_C_CPU0_SB_CA<1>
  Y49  VSS1830  POWER  = GND
  Y51  DDR2_SA_CA3  OUT  = M_C_CPU0_SA_CA<3>
  Y53  DDR2_SA_CS_N3  OUT  = M_C_CPU0_SA_CS_N<3>
  Y55  VSS1831  POWER  = GND
  Y57  DDR1_SA_DQ30  BI  = M_B_CPU0_SA_DQ<30>
  Y59  DDR1_SA_DQ27  BI  = M_B_CPU0_SA_DQ<27>
  Y61  VSS1828  POWER  = GND
  Y63  DDR2_SA_DQ22  BI  = M_C_CPU0_SA_DQ<22>
  Y65  DDR2_SA_DQ19  BI  = M_C_CPU0_SA_DQ<19>
  Y67  VSS1829  POWER  = GND
  Y69  DDR1_SA_DQ14  BI  = M_B_CPU0_SA_DQ<14>
  Y71  DDR1_SA_DQ11  BI  = M_B_CPU0_SA_DQ<11>
  Y73  VSS1833  POWER  = GND
  Y75  DDR2_SA_DQ6  BI  = M_C_CPU0_SA_DQ<6>
  Y77  DDR2_SA_DQ3  BI  = M_C_CPU0_SA_DQ<3>
  Y79  VCCFA_EHV_FIVRA102  POWER  = PVCCFA_EHV_FIVRA_CPU0
  Y81  UPI2_TX_DN9  OUT  = UPI_CPU0_CPU1_P2P2_DN<14>
  Y83  UPI2_TX_DP8  OUT  = UPI_CPU0_CPU1_P2P2_DP<15>
  Y85  VCCFA_EHV_FIVRA103  POWER  = PVCCFA_EHV_FIVRA_CPU0
  Y87  PE4_TX_DP4  OUT  = P5E_CPU0_PE4_TX_DP<4>
  Y89  VCCFA_EHV_FIVRA104  POWER  = PVCCFA_EHV_FIVRA_CPU0
  Y91  PE4_RX_DN4  IN  = P5E_CPU0_PE4_RX_DN<4>

U2_BL  TP  NA  pkg TP_BOM ONLY  page 312 : 1 = NC
U2_BP  TP  NA  pkg TP_BOM ONLY  page 312 : 1 = NC
U2_DC  TP  NA  pkg TP_BOM ONLY  page 312 : 1 = NC
